# T6G (Grand Teton) — schematic netlist excerpt (pin names and nets, part order shuffled) for the footprints in the layout excerpt that follows; sources: Cadence DE-HDL packaged netlist, KiCad conversion of 04192023_DAF0TMB3IC0_F0TG_MB_C_brd_V02_OCP.brd

PR96  Q_RES  0 5% CHIP  pkg 0402LF  page 203 : A = PVDDCR_CPU1_P0_VOS5 ; B = PVDDCR_CPU1_P0
R879  Q_RES  4.7K 5% CHIP  pkg 0201LF  page 342 : A = TEST0_RT_CPU1_P2 ; B = GND
C2619  Q_CAP  22UF 4V 20% X6S  pkg C0402  page 70 : A = PVDDIO_P0 ; B = GND

(kicad_pcb
	(version 20260206)
	(generator "pcbnew")
	(generator_version "10.0")
	(general
		(thickness 1.6)
		(legacy_teardrops no)
	)
	(paper "A4")
	(title_block
		(title "04192023_DAF0TMB3IC0_F0TG_MB_C_brd_V02_OCP.brd")
		(comment 1 "Grand Teton / footprints 8210-8212 of 8354")
	)
	(layers
		(0 "F.Cu" signal "TOP")
		(4 "In1.Cu" signal "GND")
		(6 "In2.Cu" signal "IN1")
		(8 "In3.Cu" signal "GND1")
		(10 "In4.Cu" signal "IN2")
		(12 "In5.Cu" signal "GND2")
		(14 "In6.Cu" signal "IN3")
		(16 "In7.Cu" signal "GND3")
		(18 "In8.Cu" signal "VCC")
		(20 "In9.Cu" signal "VCC1")
		(22 "In10.Cu" signal "GND4")
		(24 "In11.Cu" signal "IN4")
		(26 "In12.Cu" signal "GND5")
		(28 "In13.Cu" signal "IN5")
		(30 "In14.Cu" signal "GND6")
		(32 "In15.Cu" signal "IN6")
		(34 "In16.Cu" signal "GND7")
		(2 "B.Cu" signal "BOTTOM")
		(9 "F.Adhes" user "F.Adhesive")
		(11 "B.Adhes" user "B.Adhesive")
		(13 "F.Paste" user "Package Geometry/Pastemask Top")
		(15 "B.Paste" user "Package Geometry/Pastemask Bottom")
		(5 "F.SilkS" user "Ref Des/Silkscreen Top")
		(7 "B.SilkS" user "Ref Des/Silkscreen Bottom")
		(1 "F.Mask" user "Board Geometry/Soldermask Top")
		(3 "B.Mask" user "Board Geometry/Soldermask Bottom")
		(17 "Dwgs.User" user "User.Drawings")
		(19 "Cmts.User" user "User.Comments")
		(21 "Eco1.User" user "User.Eco1")
		(23 "Eco2.User" user "User.Eco2")
		(25 "Edge.Cuts" user "Board Geometry/Outline")
		(27 "Margin" user)
		(31 "F.CrtYd" user "Package Geometry/Place Bound Top")
		(29 "B.CrtYd" user "Package Geometry/Place Bound Bottom")
		(35 "F.Fab" user "Ref Des/Assembly Top")
		(33 "B.Fab" user "Ref Des/Assembly Bottom")
	)
	(footprint ""
		(layer "B.Cu")
		(at 348.437454 -256.73431 180)
		(property "Reference" "C2619"
			(at 0 0 0)
			(layer "B.SilkS")
			(hide yes)
			(effects
				(font
					(size 1.27 1.27)
				)
				(justify mirror)
			)
		)
		(property "Value" ""
			(at 0 0 0)
			(layer "B.Fab")
			(effects
				(font
					(size 1.27 1.27)
				)
				(justify mirror)
			)
		)
		(duplicate_pad_numbers_are_jumpers no)
		(fp_line
			(start 0.7874 0.4064)
			(end 0.7874 -0.4064)
			(stroke
				(width 0.1524)
				(type default)
			)
			(layer "B.SilkS")
		)
		(fp_line
			(start 0.7874 -0.4064)
			(end -0.7874 -0.4064)
			(stroke
				(width 0.1524)
				(type default)
			)
			(layer "B.SilkS")
		)
		(fp_line
			(start -0.7874 0.4064)
			(end 0.7874 0.4064)
			(stroke
				(width 0.1524)
				(type default)
			)
			(layer "B.SilkS")
		)
		(fp_line
			(start -0.7874 -0.4064)
			(end -0.7874 0.4064)
			(stroke
				(width 0.1524)
				(type default)
			)
			(layer "B.SilkS")
		)
		(fp_line
			(start 0.67945 0.3048)
			(end 0.67945 -0.305054)
			(stroke
				(width 0.1)
				(type default)
			)
			(layer "B.Fab")
		)
		(fp_line
			(start 0.67945 -0.305054)
			(end 0.12065 -0.305054)
			(stroke
				(width 0.1)
				(type default)
			)
			(layer "B.Fab")
		)
		(fp_line
			(start 0.12065 0.3048)
			(end 0.67945 0.3048)
			(stroke
				(width 0.1)
				(type default)
			)
			(layer "B.Fab")
		)
		(fp_line
			(start 0.12065 0.2794)
			(end 0.12065 0.3048)
			(stroke
				(width 0.1)
				(type default)
			)
			(layer "B.Fab")
		)
		(fp_line
			(start 0.12065 -0.2794)
			(end -0.12065 -0.2794)
			(stroke
				(width 0.1)
				(type default)
			)
			(layer "B.Fab")
		)
		(fp_line
			(start 0.12065 -0.305054)
			(end 0.12065 -0.2794)
			(stroke
				(width 0.1)
				(type default)
			)
			(layer "B.Fab")
		)
		(fp_line
			(start -0.120396 0.3048)
			(end -0.120396 0.2794)
			(stroke
				(width 0.1)
				(type default)
			)
			(layer "B.Fab")
		)
		(fp_line
			(start -0.120396 0.2794)
			(end 0.12065 0.2794)
			(stroke
				(width 0.1)
				(type default)
			)
			(layer "B.Fab")
		)
		(fp_line
			(start -0.12065 -0.2794)
			(end -0.12065 -0.3048)
			(stroke
				(width 0.1)
				(type default)
			)
			(layer "B.Fab")
		)
		(fp_line
			(start -0.12065 -0.3048)
			(end -0.67945 -0.3048)
			(stroke
				(width 0.1)
				(type default)
			)
			(layer "B.Fab")
		)
		(fp_line
			(start -0.67945 0.3048)
			(end -0.120396 0.3048)
			(stroke
				(width 0.1)
				(type default)
			)
			(layer "B.Fab")
		)
		(fp_line
			(start -0.67945 -0.3048)
			(end -0.67945 0.3048)
			(stroke
				(width 0.1)
				(type default)
			)
			(layer "B.Fab")
		)
		(pad "1" smd circle
			(at 0.40005 0)
			(size 0 0)
			(layers "B.Cu" "B.Mask" "B.Paste")
			(net "PVDDIO_P0")
		)
		(pad "2" smd circle
			(at -0.40005 0)
			(size 0 0)
			(layers "B.Cu" "B.Mask" "B.Paste")
			(net "GND")
		)
	)
	(footprint ""
		(layer "B.Cu")
		(at 339.72881 -337.689698 -90)
		(property "Reference" "PR96"
			(at 0 0 90)
			(layer "B.SilkS")
			(hide yes)
			(effects
				(font
					(size 1.27 1.27)
				)
				(justify mirror)
			)
		)
		(property "Value" ""
			(at 0 0 90)
			(layer "B.Fab")
			(effects
				(font
					(size 1.27 1.27)
				)
				(justify mirror)
			)
		)
		(duplicate_pad_numbers_are_jumpers no)
		(fp_line
			(start -0.7874 0.4064)
			(end 0.7874 0.4064)
			(stroke
				(width 0.1524)
				(type default)
			)
			(layer "B.SilkS")
		)
		(fp_line
			(start 0.7874 0.4064)
			(end 0.7874 -0.4064)
			(stroke
				(width 0.1524)
				(type default)
			)
			(layer "B.SilkS")
		)
		(fp_line
			(start -0.7874 -0.4064)
			(end -0.7874 0.4064)
			(stroke
				(width 0.1524)
				(type default)
			)
			(layer "B.SilkS")
		)
		(fp_line
			(start 0.7874 -0.4064)
			(end -0.7874 -0.4064)
			(stroke
				(width 0.1524)
				(type default)
			)
			(layer "B.SilkS")
		)
		(fp_line
			(start -0.67945 0.3048)
			(end -0.120396 0.3048)
			(stroke
				(width 0.1)
				(type default)
			)
			(layer "B.Fab")
		)
		(fp_line
			(start -0.120396 0.3048)
			(end -0.120396 0.2794)
			(stroke
				(width 0.1)
				(type default)
			)
			(layer "B.Fab")
		)
		(fp_line
			(start 0.12065 0.3048)
			(end 0.67945 0.3048)
			(stroke
				(width 0.1)
				(type default)
			)
			(layer "B.Fab")
		)
		(fp_line
			(start 0.67945 0.3048)
			(end 0.67945 -0.305054)
			(stroke
				(width 0.1)
				(type default)
			)
			(layer "B.Fab")
		)
		(fp_line
			(start -0.120396 0.2794)
			(end 0.12065 0.2794)
			(stroke
				(width 0.1)
				(type default)
			)
			(layer "B.Fab")
		)
		(fp_line
			(start 0.12065 0.2794)
			(end 0.12065 0.3048)
			(stroke
				(width 0.1)
				(type default)
			)
			(layer "B.Fab")
		)
		(fp_line
			(start -0.12065 -0.2794)
			(end -0.12065 -0.3048)
			(stroke
				(width 0.1)
				(type default)
			)
			(layer "B.Fab")
		)
		(fp_line
			(start 0.12065 -0.2794)
			(end -0.12065 -0.2794)
			(stroke
				(width 0.1)
				(type default)
			)
			(layer "B.Fab")
		)
		(fp_line
			(start -0.67945 -0.3048)
			(end -0.67945 0.3048)
			(stroke
				(width 0.1)
				(type default)
			)
			(layer "B.Fab")
		)
		(fp_line
			(start -0.12065 -0.3048)
			(end -0.67945 -0.3048)
			(stroke
				(width 0.1)
				(type default)
			)
			(layer "B.Fab")
		)
		(fp_line
			(start 0.12065 -0.305054)
			(end 0.12065 -0.2794)
			(stroke
				(width 0.1)
				(type default)
			)
			(layer "B.Fab")
		)
		(fp_line
			(start 0.67945 -0.305054)
			(end 0.12065 -0.305054)
			(stroke
				(width 0.1)
				(type default)
			)
			(layer "B.Fab")
		)
		(pad "1" smd circle
			(at 0.40005 0 90)
			(size 0 0)
			(layers "B.Cu" "B.Mask" "B.Paste")
			(net "PVDDCR_CPU1_P0_VOS5")
		)
		(pad "2" smd circle
			(at -0.40005 0 90)
			(size 0 0)
			(layers "B.Cu" "B.Mask" "B.Paste")
			(net "PVDDCR_CPU1_P0")
		)
	)
	(footprint ""
		(layer "B.Cu")
		(at 142.893542 -385.58216 180)
		(property "Reference" "R879"
			(at 0 0 0)
			(layer "B.SilkS")
			(hide yes)
			(effects
				(font
					(size 1.27 1.27)
				)
				(justify mirror)
			)
		)
		(property "Value" ""
			(at 0 0 0)
			(layer "B.Fab")
			(effects
				(font
					(size 1.27 1.27)
				)
				(justify mirror)
			)
		)
		(duplicate_pad_numbers_are_jumpers no)
		(fp_line
			(start 0.32512 0.175006)
			(end 0.32512 -0.175006)
			(stroke
				(width 0.1)
				(type default)
			)
			(layer "B.Fab")
		)
		(fp_line
			(start 0.32512 -0.175006)
			(end -0.32512 -0.175006)
			(stroke
				(width 0.1)
				(type default)
			)
			(layer "B.Fab")
		)
		(fp_line
			(start -0.32512 0.175006)
			(end 0.32512 0.175006)
			(stroke
				(width 0.1)
				(type default)
			)
			(layer "B.Fab")
		)
		(fp_line
			(start -0.32512 -0.175006)
			(end -0.32512 0.175006)
			(stroke
				(width 0.1)
				(type default)
			)
			(layer "B.Fab")
		)
		(pad "1" smd rect
			(at 0.2667 0)
			(size 0.3048 0.381)
			(layers "B.Cu" "B.Mask" "B.Paste")
			(net "TEST0_RT_CPU1_P2")
		)
		(pad "2" smd rect
			(at -0.2667 0 180)
			(size 0.3048 0.381)
			(layers "B.Cu" "B.Mask" "B.Paste")
			(net "GND")
		)
	)
)
